FILE_TYPE = CONNECTIVITY;
{Allegro Design Entry HDL 16.6-p007 (v16-6-112F) 10/10/2012}
"PAGE_NUMBER" = 21;
0"NC";
1"PVCCIO_CPU0\g";
2"GND\g";
3"GND\g";
4"P3V3_STBY\g";
5"P3V3_STBY\g";
6"PVCCIO_CPU0\g";
7"PU_CPU0_EAR_N";
8"H_PM_SYNC_GTL";
9"H_PMSYNC_CLK_24M";
10"PECI_CPU_G";
11"RST_CPU0_G_N";
12"PWRGD_CPU0_G";
13"H_PM_SYNC_GTL_R1";
14"H_PMSYNC_CLK_24M_CPU0";
15"SVID_DIO1_CPU0_R";
16"SVID_ALERT1_CPU0_R_N";
17"SVID_ALERT0_CPU0_R_N";
18"FM_CPU0_PROC_ID1";
19"SVID_CLK1_CPU0_R";
20"SVID_CLK0_CPU0_R";
21"SVID_DIO0_CPU0_R";
22"H_CPU0_THERMTRIP_G_N";
23"H_CPU0_PROCHOT_G_N";
24"H_CPU0_ERR0_G_N";
25"H_CPU0_ERR1_G_N";
26"H_CPU0_ERR2_G_N";
27"H_CPU0_CATERR_G_N";
28"PD_PIROM_CPU0_ADDR1";
29"PD_PIROM_CPU0_ADDR2";
30"XDP_CPU_PRDY_N";
31"XDP_CPU_PREQ_N";
32"PD_CPU0_TEST12";
33"PU_CPU0_LEGACY_SKT";
34"PU_CPU0_TSC_SYNC";
35"H_CPU0_MSMI_G_N";
36"TP_CPU0_PROCDIS_G_N";
37"H_CPU0_FAST_WAKE_N";
38"PD_CPU0_BIST_ENABLE";
39"PD_CPU0_TXT_PLTEN";
40"PU_CPU0_TXT_AGENT";
41"H_CPU0_BMCINIT";
42"PU_CPU0_FRMAGENT";
43"PU_CPU0_SAFE_MODE_BOOT";
44"PU_CPU0_SOCKET_ID_1";
45"PU_CPU0_SOCKET_ID_0";
46"TP_CPU0_SOCKET_ID_2";
47"SVID_DIO0_CPU0";
48"SVID_ALERT1_CPU0_N";
49"SVID_CLK1_CPU0";
50"SVID_DIO1_CPU0";
51"SVID_CLK0_CPU0";
52"SVID_ALERT0_CPU0_N";
53"CLK_100M_CPU0_BCLK1_DN";
54"CLK_100M_CPU0_BCLK1_DP";
55"CLK_100M_CPU0_BCLK0_DN";
56"CLK_100M_CPU0_BCLK0_DP";
57"CLK_100M_CPU0_BCLK2_DN";
58"CLK_100M_CPU0_BCLK2_DP";
59"SMB_DDR_ABC_SCL_G_R";
60"SMB_DDR_DEF_SCL_G_R";
61"SMB_DDR_ABC_SDA_G_R";
62"SMB_DDR_DEF_SDA_G_R";
63"M_ABC_RST_N";
64"PWRGD_CPU0_DRAMPWROK_DEF_G";
65"PWRGD_CPU0_DRAMPWROK_ABC_G";
66"XDP_CPU_TRST_N";
67"XDP_CPU_TMS";
68"XDP_CPU_TCK0";
69"XDP_CPU_TDI";
70"XDP_CPU_MBP0_N";
71"XDP_CPU_MBP1_N";
72"SMB_PIROM_CPU0_SDA";
73"SMB_PIROM_CPU0_SCL";
74"XDP_CPU_OBSFN_B0_MBP6_N";
75"M_C_CPU_VREF";
76"M_B_CPU_VREF";
77"M_E_CPU_VREF";
78"M_F_CPU_VREF";
79"M_A_CPU_VREF";
80"XDP_CPU_OBSFN_B1_MBP7_N";
81"M_D_CPU_VREF";
82"H_CPU0_MEMDEF_MEMHOT_G_N";
83"H_CPU0_MEMABC_MEMHOT_G_N";
84"M_DEF_RST_N";
85"A_CPU0_DEF_RCOMP1";
86"A_CPU0_DEF_RCOMP2";
87"A_CPU0_ABC_RCOMP0";
88"A_CPU0_DEF_RCOMP0";
89"TP_CPU0_PE_HP_SDA";
90"A_CPU0_ABC_RCOMP2";
91"A_CPU0_ABC_RCOMP1";
92"A_CPU0_PE3_RBIAS";
93"A_CPU0_PE012_RBIAS";
94"TP_CPU0_PE_HP_SCL";
95"A_CPU0_UPI01_RBIAS";
96"A_CPU0_MCP01_RBIAS";
97"A_CPU0_UPI2_RBIAS";
98"TP_XDP_CPU0_OBSDATA_A3_MBP5_N";
99"TP_XDP_CPU0_OBSDATA_A2_MBP4_N";
100"TP_XDP_CPU0_OBSDATA_A1_MBP3_N";
101"TP_XDP_CPU0_OBSDATA_A0_MBP2_N";
102"FM_CPU0_PROC_ID0";
103"FM_CPU0_SM_WP";
104"PD_PIROM_CPU0_ADDR0";
105"XDP_CPU0_TDO";
106"FM_CPU0_SKTOCC_LVT3_N";
107"TP_NMI_CPU0";
108"FM_CPU0_PKGID2";
109"FM_CPU0_PKGID1";
110"FM_CPU0_PKGID0";
111"PD_CPU0_TEST13";
112"PD_CPU0_KSFC_DIS";
113"PD_CPU0_TEST14";
%"RES"
"1","(-1975,3750)","0","mstr_discrete","I149";
;
CDS_SEC"1"
ROOM"CPU0"
CDS_LOCATION"R6N10"
SEC"1"
SEC_TYPE"0402"
BOM_COST"PROC_SIDEBAND"
CDS_LIB"mstr_discrete"
WATTAGE"1/16W"
MATERIAL"CHIP"
PACK_TYPE"0402"
TOLERANCE"1.0%"
VALUE"221"
PART_NUMBER"G21796-271"
LOCATION"R6N10";
"B"
$PN"2"17;
"A"
$PN"1"52;
%"RES"
"1","(-1975,3800)","0","mstr_discrete","I150";
;
CDS_SEC"1"
ROOM"CPU0"
CDS_LOCATION"R6N12"
SEC"1"
SEC_TYPE"0402"
BOM_COST"PROC_SIDEBAND"
CDS_LIB"mstr_discrete"
WATTAGE"1/16W"
MATERIAL"CHIP"
PACK_TYPE"0402"
TOLERANCE"5%"
VALUE"0.0"
PART_NUMBER"G21497-005"
LOCATION"R6N12";
"B"
$PN"2"20;
"A"
$PN"1"51;
%"RES"
"1","(-1975,3850)","0","mstr_discrete","I151";
;
CDS_SEC"1"
ROOM"CPU0"
CDS_LOCATION"R6N11"
SEC"1"
SEC_TYPE"0402"
BOM_COST"PROC_SIDEBAND"
CDS_LIB"mstr_discrete"
WATTAGE"1/16W"
MATERIAL"CHIP"
PACK_TYPE"0402"
TOLERANCE"5%"
VALUE"0.0"
PART_NUMBER"G21497-005"
LOCATION"R6N11";
"B"
$PN"2"21;
"A"
$PN"1"47;
%"RES"
"1","(-1975,3900)","0","mstr_discrete","I152";
;
CDS_SEC"1"
ROOM"CPU0"
CDS_LOCATION"R6B3"
SEC"1"
CDS_LIB"mstr_discrete"
BOM_COST"PROC_SIDEBAND"
SEC_TYPE"0402"
WATTAGE"1/16W"
MATERIAL"CHIP"
PACK_TYPE"0402"
TOLERANCE"1.0%"
VALUE"221"
PART_NUMBER"G21796-271"
LOCATION"R6B3";
"B"
$PN"2"16;
"A"
$PN"1"48;
%"RES"
"1","(-1975,3950)","0","mstr_discrete","I153";
;
CDS_SEC"1"
ROOM"CPU0"
CDS_LOCATION"R6B5"
SEC"1"
SEC_TYPE"0402"
CDS_LIB"mstr_discrete"
BOM_COST"PROC_SIDEBAND"
WATTAGE"1/16W"
MATERIAL"CHIP"
PACK_TYPE"0402"
TOLERANCE"5%"
VALUE"0.0"
PART_NUMBER"G21497-005"
LOCATION"R6B5";
"B"
$PN"2"19;
"A"
$PN"1"49;
%"RES"
"1","(-1975,4000)","0","mstr_discrete","I154";
;
CDS_SEC"1"
ROOM"CPU0"
CDS_LOCATION"R6B4"
SEC"1"
SEC_TYPE"0402"
CDS_LIB"mstr_discrete"
BOM_COST"PROC_SIDEBAND"
WATTAGE"1/16W"
MATERIAL"CHIP"
PACK_TYPE"0402"
TOLERANCE"5%"
VALUE"0.0"
PART_NUMBER"G21497-005"
LOCATION"R6B4";
"B"
$PN"2"15;
"A"
$PN"1"50;
%"PVCCIO_CPU0"
"1","(-975,4625)","0","mstr_symbols","I158";
;
HDL_POWER"PVCCIO_CPU0"
BODY_TYPE"PLUMBING"
CDS_LIB"mstr_symbols"
VOLTAGE"1.1V";
"G\NAC"1;
%"RES"
"2","(-1200,4300)","0","mstr_discrete","I159";
;
CDS_SEC"1"
ROOM"CPU0"
CDS_LOCATION"R6B2"
SEC"1"
SEC_TYPE"0402"
CDS_LIB"mstr_discrete"
BOM_COST"PROC_SIDEBAND"
WATTAGE"1/16W"
PACK_TYPE"0402"
TOLERANCE"1%"
MATERIAL"CHIP"
VALUE"100.0"
PART_NUMBER"G21796-017"
LOCATION"R6B2";
"A"
$PN"1"1;
"B"
$PN"2"15;
%"RES"
"2","(-975,4300)","0","mstr_discrete","I161";
;
CDS_SEC"1"
ROOM"CPU0"
CDS_LOCATION"R6B1"
SEC"1"
CDS_LIB"mstr_discrete"
BOM_COST"PROC_SIDEBAND"
SEC_TYPE"0402"
WATTAGE"1/16W"
PACK_TYPE"0402"
TOLERANCE"1%"
MATERIAL"CHIP"
VALUE"49.9"
PART_NUMBER"G21796-047"
LOCATION"R6B1";
"A"
$PN"1"1;
"B"
$PN"2"16;
%"RES"
"2","(-1200,3475)","0","mstr_discrete","I163";
;
CDS_SEC"1"
ROOM"CPU0"
CDS_LOCATION"R6N2"
SEC"1"
SEC_TYPE"0402"
CDS_LIB"mstr_discrete"
BOM_COST"PROC_SIDEBAND"
WATTAGE"1/16W"
PACK_TYPE"0402"
TOLERANCE"1%"
MATERIAL"CHIP"
VALUE"100.0"
PART_NUMBER"G21796-017"
LOCATION"R6N2";
"A"
$PN"1"21;
"B"
$PN"2"6;
%"RES"
"2","(-975,3500)","0","mstr_discrete","I164";
;
CDS_SEC"1"
ROOM"CPU0"
CDS_LOCATION"R6N1"
SEC"1"
BOM_COST"PROC_SIDEBAND"
CDS_LIB"mstr_discrete"
SEC_TYPE"0402"
WATTAGE"1/16W"
PACK_TYPE"0402"
TOLERANCE"1%"
MATERIAL"CHIP"
VALUE"49.9"
PART_NUMBER"G21796-047"
LOCATION"R6N1";
"A"
$PN"1"17;
"B"
$PN"2"6;
%"RES"
"2","(-6625,2875)","2","mstr_discrete","I177";
;
CDS_SEC"1"
ROOM"CPU0"
CDS_LOCATION"R5D1"
SEC"1"
BOM_COST"PROC_SOCKET"
CDS_LIB"mstr_discrete"
SEC_TYPE"0402"
WATTAGE"1/16W"
MATERIAL"CHIP"
PACK_TYPE"0402"
TOLERANCE"1%"
VALUE"90.9"
PART_NUMBER"G21796-365"
LOCATION"R5D1";
"A"
$PN"1"88;
"B"
$PN"2"2;
%"RES"
"2","(-6875,2925)","2","mstr_discrete","I178";
;
CDS_SEC"1"
ROOM"CPU0"
CDS_LOCATION"R5D2"
SEC"1"
BOM_COST"PROC_SOCKET"
CDS_LIB"mstr_discrete"
SEC_TYPE"0402"
WATTAGE"1/16W"
MATERIAL"CHIP"
PACK_TYPE"0402"
TOLERANCE"1%"
VALUE"90.9"
PART_NUMBER"G21796-365"
LOCATION"R5D2";
"A"
$PN"1"85;
"B"
$PN"2"2;
%"RES"
"2","(-7125,2925)","2","mstr_discrete","I179";
;
CDS_SEC"1"
ROOM"CPU0"
CDS_LOCATION"R6D1"
SEC"1"
BOM_COST"PROC_SOCKET"
CDS_LIB"mstr_discrete"
SEC_TYPE"0402"
WATTAGE"1/16W"
MATERIAL"CHIP"
PACK_TYPE"0402"
TOLERANCE"1%"
VALUE"100.0"
PART_NUMBER"G21796-017"
LOCATION"R6D1";
"A"
$PN"1"86;
"B"
$PN"2"2;
%"RES"
"2","(-7350,2925)","2","mstr_discrete","I180";
;
CDS_SEC"1"
ROOM"CPU0"
CDS_LOCATION"R4P8"
SEC"1"
BOM_COST"PROC_SOCKET"
CDS_LIB"mstr_discrete"
SEC_TYPE"0402"
WATTAGE"1/16W"
MATERIAL"CHIP"
PACK_TYPE"0402"
TOLERANCE"1%"
VALUE"90.9"
PART_NUMBER"G21796-365"
LOCATION"R4P8";
"A"
$PN"1"87;
"B"
$PN"2"2;
%"RES"
"2","(-7575,3000)","2","mstr_discrete","I181";
;
CDS_SEC"1"
ROOM"CPU0"
CDS_LOCATION"R4P10"
SEC"1"
BOM_COST"PROC_SOCKET"
CDS_LIB"mstr_discrete"
SEC_TYPE"0402"
WATTAGE"1/16W"
MATERIAL"CHIP"
PACK_TYPE"0402"
TOLERANCE"1%"
VALUE"90.9"
PART_NUMBER"G21796-365"
LOCATION"R4P10";
"A"
$PN"1"91;
"B"
$PN"2"2;
%"RES"
"2","(-7800,3000)","2","mstr_discrete","I182";
;
CDS_SEC"1"
ROOM"CPU0"
CDS_LOCATION"R4P11"
SEC"1"
BOM_COST"PROC_SOCKET"
CDS_LIB"mstr_discrete"
SEC_TYPE"0402"
WATTAGE"1/16W"
MATERIAL"CHIP"
PACK_TYPE"0402"
TOLERANCE"1%"
VALUE"100.0"
PART_NUMBER"G21796-017"
LOCATION"R4P11";
"A"
$PN"1"90;
"B"
$PN"2"2;
%"GND"
"1","(-7800,2575)","0","mstr_symbols","I183";
;
HDL_POWER"GND"
BODY_TYPE"PLUMBING"
CDS_LIB"mstr_symbols"
SIZE"1B"
VOLTAGE"0.0V";
"A\NAC"2;
%"RES"
"2","(-7375,2100)","2","mstr_discrete","I184";
;
CDS_SEC"1"
ROOM"CPU0"
CDS_LOCATION"R6D11"
SEC"1"
SEC_TYPE"0402"
BOM_COST"PROC_SOCKET"
CDS_LIB"mstr_discrete"
WATTAGE"1/16W"
MATERIAL"CHIP"
PACK_TYPE"0402"
TOLERANCE"1%"
VALUE"49.9"
PART_NUMBER"G21796-047"
LOCATION"R6D11";
"A"
$PN"1"95;
"B"
$PN"2"3;
%"RES"
"2","(-7575,2100)","2","mstr_discrete","I186";
;
CDS_SEC"1"
ROOM"CPU0"
CDS_LOCATION"R4P3"
SEC"1"
SEC_TYPE"0402"
BOM_COST"PROC_SOCKET"
CDS_LIB"mstr_discrete"
WATTAGE"1/16W"
MATERIAL"CHIP"
PACK_TYPE"0402"
TOLERANCE"1%"
VALUE"49.9"
PART_NUMBER"G21796-047"
LOCATION"R4P3";
"A"
$PN"1"93;
"B"
$PN"2"3;
%"GND"
"1","(-7800,1725)","0","mstr_symbols","I187";
;
HDL_POWER"GND"
BODY_TYPE"PLUMBING"
CDS_LIB"mstr_symbols"
SIZE"1B"
VOLTAGE"0.0V";
"A\NAC"3;
%"RES"
"2","(-7800,2100)","2","mstr_discrete","I188";
;
CDS_SEC"1"
ROOM"CPU0"
CDS_LOCATION"R4P2"
SEC"1"
SEC_TYPE"0402"
BOM_COST"PROC_SOCKET"
CDS_LIB"mstr_discrete"
WATTAGE"1/16W"
MATERIAL"CHIP"
PACK_TYPE"0402"
TOLERANCE"1%"
VALUE"49.9"
PART_NUMBER"G21796-047"
LOCATION"R4P2";
"A"
$PN"1"92;
"B"
$PN"2"3;
%"RES"
"2","(-7150,2050)","2","mstr_discrete","I189";
;
CDS_SEC"1"
ROOM"CPU0"
CDS_LOCATION"R4P4"
SEC"1"
CDS_LIB"mstr_discrete"
BOM_COST"PROC_SOCKET"
SEC_TYPE"0402"
WATTAGE"1/16W"
MATERIAL"CHIP"
PACK_TYPE"0402"
TOLERANCE"1%"
VALUE"49.9"
PART_NUMBER"G21796-047"
LOCATION"R4P4";
"A"
$PN"1"97;
"B"
$PN"2"3;
%"RES"
"2","(-6925,2000)","2","mstr_discrete","I204";
;
CDS_SEC"1"
ROOM"CPU0"
CDS_LOCATION"R6D2"
SEC"1"
SEC_TYPE"0402"
BOM_COST"PROC_SOCKET"
CDS_LIB"mstr_discrete"
WATTAGE"1/16W"
MATERIAL"CHIP"
PACK_TYPE"0402"
TOLERANCE"1%"
VALUE"49.9"
PART_NUMBER"G21796-047"
LOCATION"R6D2";
"A"
$PN"1"96;
"B"
$PN"2"3;
%"SOCKET_P_MECH_A"
"1","(-7525,4450)","0","chpset_lib","I216";
;
ROOM"CPU0"
CDS_LOCATION"XRU1"
BOM_COST"PROC_SOCKET"
CDS_LIB"chpset_lib"
LOCATION"XRU1"
SKT_NUMBER"P0"
PART_NUMBER"H37604-101"
MATERIAL"PLASTIC"
PACK_TYPE"RIGHT";
%"SOCKET_P_MECH_A"
"1","(-7525,4150)","0","chpset_lib","I217";
;
ROOM"CPU0"
CDS_LOCATION"XLU1"
CDS_LIB"chpset_lib"
BOM_COST"PROC_SOCKET"
PACK_TYPE"LEFT"
LOCATION"XLU1"
SKT_NUMBER"P0"
PART_NUMBER"H37604-201"
MATERIAL"PLASTIC";
%"RES"
"1","(-2375,4200)","0","mstr_discrete","I219";
;
CDS_SEC"1"
ROOM"CPU0"
CDS_LOCATION"R4P19"
SEC"1"
BOM_COST"PROC_SOCKET"
SEC_TYPE"0402"
CDS_LIB"mstr_discrete"
WATTAGE"1/16W"
MATERIAL"CHIP"
PACK_TYPE"0402"
TOLERANCE"1%"
VALUE"49.9"
PART_NUMBER"G21796-047"
LOCATION"R4P19";
"B"
$PN"2"9;
"A"
$PN"1"14;
%"RES"
"2","(-1475,2700)","0","mstr_discrete","I227";
;
CDS_SEC"1"
ROOM"CPU0"
CDS_LOCATION"R5N2"
SEC"1"
BOM_COST"PROC_SIDEBAND"
SEC_TYPE"0402"
CDS_LIB"mstr_discrete"
WATTAGE"1/16W"
MATERIAL"CHIP"
PACK_TYPE"0402"
TOLERANCE"1%"
VALUE"1.8K"
PART_NUMBER"G21796-336"
LOCATION"R5N2";
"A"
$PN"1"4;
"B"
$PN"2"18;
%"P3V3_STBY"
"1","(-675,3050)","0","mstr_symbols","I228";
;
HDL_POWER"P3V3_STBY"
BODY_TYPE"PLUMBING"
SIZE"1B"
CDS_LIB"mstr_symbols"
VOLTAGE"3.3V";
"G\NAC"4;
%"RES"
"2","(-675,2700)","0","mstr_discrete","I238";
;
CDS_SEC"1"
ROOM"CPU0"
CDS_LOCATION"R5N1"
SEC"1"
BOM_COST"PROC_SIDEBAND"
SEC_TYPE"0402"
CDS_LIB"mstr_discrete"
WATTAGE"1/16W"
MATERIAL"CHIP"
PACK_TYPE"0402"
TOLERANCE"1%"
VALUE"10.0K"
PART_NUMBER"G21796-016"
LOCATION"R5N1";
"A"
$PN"1"4;
"B"
$PN"2"110;
%"RES"
"2","(-875,2700)","0","mstr_discrete","I239";
;
CDS_SEC"1"
ROOM"CPU0"
CDS_LOCATION"R5N5"
SEC"1"
BOM_COST"PROC_SIDEBAND"
SEC_TYPE"0402"
CDS_LIB"mstr_discrete"
WATTAGE"1/16W"
MATERIAL"CHIP"
PACK_TYPE"0402"
TOLERANCE"1%"
VALUE"10.0K"
PART_NUMBER"G21796-016"
LOCATION"R5N5";
"A"
$PN"1"4;
"B"
$PN"2"109;
%"RES"
"2","(-1075,2700)","0","mstr_discrete","I240";
;
CDS_SEC"1"
ROOM"CPU0"
CDS_LOCATION"R5N3"
SEC"1"
BOM_COST"PROC_SIDEBAND"
SEC_TYPE"0402"
CDS_LIB"mstr_discrete"
WATTAGE"1/16W"
MATERIAL"CHIP"
PACK_TYPE"0402"
TOLERANCE"1%"
VALUE"10.0K"
PART_NUMBER"G21796-016"
LOCATION"R5N3";
"A"
$PN"1"4;
"B"
$PN"2"108;
%"RES"
"2","(-1275,2700)","0","mstr_discrete","I241";
;
CDS_SEC"1"
ROOM"CPU0"
CDS_LOCATION"R5N4"
SEC"1"
BOM_COST"PROC_SIDEBAND"
SEC_TYPE"0402"
CDS_LIB"mstr_discrete"
WATTAGE"1/16W"
MATERIAL"CHIP"
PACK_TYPE"0402"
TOLERANCE"1%"
VALUE"1.8K"
PART_NUMBER"G21796-336"
LOCATION"R5N4";
"A"
$PN"1"4;
"B"
$PN"2"102;
%"P3V3_STBY"
"1","(-1075,1725)","0","mstr_symbols","I243";
;
HDL_POWER"P3V3_STBY"
BODY_TYPE"PLUMBING"
SIZE"1B"
CDS_LIB"mstr_symbols"
VOLTAGE"3.3V";
"G\NAC"5;
%"RES"
"1","(-2450,4250)","0","mstr_discrete","I244";
;
CDS_SEC"1"
ROOM"CPU0"
CDS_LOCATION"R4P18"
SEC"1"
BOM_COST"PROC_SIDEBAND"
CDS_LIB"mstr_discrete"
SEC_TYPE"0402"
WATTAGE"1/16W"
MATERIAL"CHIP"
PACK_TYPE"0402"
TOLERANCE"1%"
VALUE"49.9"
PART_NUMBER"G21796-047"
LOCATION"R4P18";
"B"
$PN"2"8;
"A"
$PN"1"13;
%"PVCCIO_CPU0"
"1","(-650,3375)","0","mstr_symbols","I257";
;
HDL_POWER"PVCCIO_CPU0"
BODY_TYPE"PLUMBING"
CDS_LIB"mstr_symbols"
VOLTAGE"1.1V";
"G\NAC"6;
%"RES"
"2","(-1075,1450)","0","mstr_discrete","I258";
;
CDS_SEC"1"
ROOM"CPU0"
CDS_LOCATION"R4R5"
SEC"1"
SEC_TYPE"0402"
CDS_LIB"mstr_discrete"
PART_NUMBER"G21796-072"
MATERIAL"CHIP"
LOCATION"R4R5"
PACK_TYPE"0402"
WATTAGE"1/16W"
TOLERANCE"1%"
VALUE"4.75K";
"A"
$PN"1"5;
"B"
$PN"2"106;
%"SKX_EXT_B"
"1","(-4075,2850)","0","chpset_lib","I259";
;
CDS_SEC"1"
ROOM"CPU0"
CDS_LOCATION"U5D1"
SEC"1"
SEC_TYPE"BGA1"
CDS_LIB"chpset_lib"
PACK_TYPE"BGA1"
MATERIAL"IC"
PART_NUMBER"TBD"
LOCATION"U5D1";
"UPI2_RBIAS<0>"
$PN"CL28"97;
"UPI2_RBIAS<1>"
$PN"CK29"97;
"UPI01_RBIAS<0>"
$PN"AT29"95;
"UPI01_RBIAS<1>"
$PN"AP29"95;
"TXT_PLTEN"
$PN"AV15"39;
"TXT_AGENT"
$PN"AW18"40;
"TSC_SYNC"
$PN"AM11"34;
"TRST_N"
$PN"Y13"66;
"TMS"
$PN"W14"67;
"THERMTRIP_N"
$PN"AB15"22;
"TEST_15"
$PN"AW14"112;
"TEST_14"
$PN"DC50"113;
"TEST_13"
$PN"DB51"111;
"TEST_12"
$PN"AY19"32;
"TDO"
$PN"AE14"105;
"TDI"
$PN"AC14"69;
"TCK"
$PN"AA14"68;
"SVIDDATA<0>"
$PN"DB45"47;
"SVIDDATA<1>"
$PN"DJ44"50;
"SVIDCLK<0>"
$PN"DC44"51;
"SVIDCLK<1>"
$PN"DG44"49;
"SVIDALERT_N<0>"
$PN"DE44"52;
"SVIDALERT_N<1>"
$PN"DL44"48;
"SOCKET_ID<0>"
$PN"AU22"45;
"SOCKET_ID<1>"
$PN"AU16"44;
"SOCKET_ID<2>"
$PN"AU20"46;
"SM_WP"
$PN"CV59"103;
"SMBDAT"
$PN"CW58"72;
"SMBCLK"
$PN"CT59"73;
"SKTOCC_N"
$PN"AB13"106;
"SAFE_MODE_BOOT"
$PN"AR18"43;
"RESET_N"
$PN"AP21"11;
"PWRGOOD"
$PN"BC24"12;
"PROC_ID<0>"
$PN"CY71"102;
"PROC_ID<1>"
$PN"DB71"18;
"PROCHOT_N"
$PN"AC16"23;
"PROCDIS_N"
$PN"AB17"36;
"PREQ_N"
$PN"AR12"31;
"PRDY_N"
$PN"AG16"30;
"PM_FAST_WAKE_N"
$PN"AF15"37;
"PMSYNC_CLK"
$PN"AT19"14;
"PMSYNC"
$PN"AR14"13;
"PKGID<0>"
$PN"DC72"110;
"PKGID<1>"
$PN"CW72"109;
"PKGID<2>"
$PN"DA72"108;
"PIROM_ADDR<0>"
$PN"CU58"104;
"PIROM_ADDR<1>"
$PN"CV57"28;
"PIROM_ADDR<2>"
$PN"CW56"29;
"PE_HP_SDA"
$PN"AL18"89;
"PE_HP_SCL"
$PN"AM19"94;
"PECI"
$PN"AU12"10;
"PE3_RBIAS<0>"
$PN"CP29"92;
"PE3_RBIAS<1>"
$PN"CR30"92;
"PE012_RBIAS<0>"
$PN"CN30"93;
"PE012_RBIAS<1>"
$PN"CL30"93;
"NMI"
$PN"AP11"107;
"MSMI_N"
$PN"AN20"35;
"MEM_HOT_C345_N"
$PN"AF13"82;
"MEM_HOT_C012_N"
$PN"AH13"83;
"MCP01_RBIAS<0>"
$PN"CU32"96;
"MCP01_RBIAS<1>"
$PN"CT31"96;
"LEGACY_SKT"
$PN"AE20"33;
"FRMAGENT"
$PN"AV17"42;
"ERROR_N<0>"
$PN"AJ12"24;
"ERROR_N<1>"
$PN"AK11"25;
"ERROR_N<2>"
$PN"AL12"26;
"EAR_N"
$PN"AJ14"7;
"DDR5_CAVREF"
$PN"CV61"78;
"DDR4_CAVREF"
$PN"CT61"77;
"DDR3_CAVREF"
$PN"CP61"81;
"DDR345_SPDSDA"
$PN"AD17"62;
"DDR345_SPDSCL"
$PN"AE18"60;
"DDR345_RESET_N"
$PN"DV63"84;
"DDR345_RCOMP<0>"
$PN"DC48"88;
"DDR345_RCOMP<1>"
$PN"DD47"85;
"DDR345_RCOMP<2>"
$PN"DD49"86;
"DDR345_DRAM_PWR_OK"
$PN"CR28"64;
"DDR2_CAVREF"
$PN"AH63"75;
"DDR1_CAVREF"
$PN"AK63"76;
"DDR0_CAVREF"
$PN"AJ64"79;
"DDR012_SPDSDA"
$PN"AF17"61;
"DDR012_SPDSCL"
$PN"AJ18"59;
"DDR012_RESET_N"
$PN"U64"63;
"DDR012_RCOMP<0>"
$PN"Y43"87;
"DDR012_RCOMP<1>"
$PN"AB43"91;
"DDR012_RCOMP<2>"
$PN"AC42"90;
"DDR012_DRAM_PWR_OK"
$PN"AN30"65;
"CATERR_N"
$PN"AL14"27;
"BPM_N<0>"
$PN"AJ10"70;
"BPM_N<1>"
$PN"AH11"71;
"BPM_N<2>"
$PN"AG10"101;
"BPM_N<3>"
$PN"AF11"100;
"BPM_N<4>"
$PN"AA12"99;
"BPM_N<5>"
$PN"Y11"98;
"BPM_N<6>"
$PN"AE12"74;
"BPM_N<7>"
$PN"AC12"80;
"BMCINIT"
$PN"BD23"41;
"BIST_ENABLE"
$PN"BA20"38;
"BCLK2_DP"
$PN"CU26"58;
"BCLK2_DN"
$PN"CT25"57;
"BCLK1_DP"
$PN"CP27"54;
"BCLK1_DN"
$PN"CR26"53;
"BCLK0_DP"
$PN"AW24"56;
"BCLK0_DN"
$PN"AU24"55;
END.
